# T6G (Grand Teton) — schematic netlist excerpt (pin names and nets, part order shuffled) for the footprints in the layout excerpt that follows; sources: Cadence DE-HDL packaged netlist, KiCad conversion of 04192023_DAF0TMB3IC0_F0TG_MB_C_brd_V02_OCP.brd

J8069  PICOPROBE_BXA  DELTA-L 4.0 EMPTY  pkg TRIANG_LAUNCH_3PXB  page 229
  \1_p\  = DELTA_L_85_5INCH_TOP_DN
  \2_n\  = DELTA_L_85_5INCH_TOP_DP
  \3_g\  = DELTA_L_GND_1

(kicad_pcb
	(version 20260206)
	(generator "pcbnew")
	(generator_version "10.0")
	(general
		(thickness 1.6)
		(legacy_teardrops no)
	)
	(paper "A4")
	(title_block
		(title "04192023_DAF0TMB3IC0_F0TG_MB_C_brd_V02_OCP.brd")
		(comment 1 "Grand Teton / footprints 757-757 of 8354")
	)
	(layers
		(0 "F.Cu" signal "TOP")
		(4 "In1.Cu" signal "GND")
		(6 "In2.Cu" signal "IN1")
		(8 "In3.Cu" signal "GND1")
		(10 "In4.Cu" signal "IN2")
		(12 "In5.Cu" signal "GND2")
		(14 "In6.Cu" signal "IN3")
		(16 "In7.Cu" signal "GND3")
		(18 "In8.Cu" signal "VCC")
		(20 "In9.Cu" signal "VCC1")
		(22 "In10.Cu" signal "GND4")
		(24 "In11.Cu" signal "IN4")
		(26 "In12.Cu" signal "GND5")
		(28 "In13.Cu" signal "IN5")
		(30 "In14.Cu" signal "GND6")
		(32 "In15.Cu" signal "IN6")
		(34 "In16.Cu" signal "GND7")
		(2 "B.Cu" signal "BOTTOM")
		(9 "F.Adhes" user "F.Adhesive")
		(11 "B.Adhes" user "B.Adhesive")
		(13 "F.Paste" user "Package Geometry/Pastemask Top")
		(15 "B.Paste" user "Package Geometry/Pastemask Bottom")
		(5 "F.SilkS" user "Ref Des/Silkscreen Top")
		(7 "B.SilkS" user "Ref Des/Silkscreen Bottom")
		(1 "F.Mask" user "Board Geometry/Soldermask Top")
		(3 "B.Mask" user "Board Geometry/Soldermask Bottom")
		(17 "Dwgs.User" user "User.Drawings")
		(19 "Cmts.User" user "User.Comments")
		(21 "Eco1.User" user "User.Eco1")
		(23 "Eco2.User" user "User.Eco2")
		(25 "Edge.Cuts" user "Board Geometry/Outline")
		(27 "Margin" user)
		(31 "F.CrtYd" user "Package Geometry/Place Bound Top")
		(29 "B.CrtYd" user "Package Geometry/Place Bound Bottom")
		(35 "F.Fab" user "Ref Des/Assembly Top")
		(33 "B.Fab" user "Ref Des/Assembly Bottom")
	)
	(footprint ""
		(layer "F.Cu")
		(at 314.965588 -5.077206)
		(property "Reference" "J8069"
			(at -4.58978 1.628648 90)
			(unlocked yes)
			(layer "F.SilkS")
			(effects
				(font
					(size 0.7874 0.5842)
					(thickness 0.1524)
				)
				(justify left)
			)
		)
		(property "Value" ""
			(at 0 0 0)
			(layer "F.Fab")
			(effects
				(font
					(size 1.27 1.27)
				)
			)
		)
		(duplicate_pad_numbers_are_jumpers no)
		(fp_line
			(start -1.2192 -2.06756)
			(end 1.2192 -2.06756)
			(stroke
				(width 0.1524)
				(type default)
			)
			(layer "F.SilkS")
		)
		(fp_line
			(start -1.2192 2.06756)
			(end -1.2192 -2.06756)
			(stroke
				(width 0.1524)
				(type default)
			)
			(layer "F.SilkS")
		)
		(fp_line
			(start 1.2192 -2.06756)
			(end 1.2192 2.06756)
			(stroke
				(width 0.1524)
				(type default)
			)
			(layer "F.SilkS")
		)
		(fp_line
			(start 1.2192 2.06756)
			(end -1.2192 2.06756)
			(stroke
				(width 0.1524)
				(type default)
			)
			(layer "F.SilkS")
		)
		(pad "" np_thru_hole circle
			(at -2.8829 -1.27 270)
			(size 1.0414 1.0414)
			(drill 1.0414)
			(layers "*.Cu" "*.Mask")
			(clearance 0.381)
			(thermal_gap 0.381)
		)
		(pad "" np_thru_hole circle
			(at -2.8829 1.27 270)
			(size 1.0414 1.0414)
			(drill 1.0414)
			(layers "*.Cu" "*.Mask")
			(clearance 0.381)
			(thermal_gap 0.381)
		)
		(pad "" np_thru_hole circle
			(at 3.4671 -1.27 270)
			(size 1.0414 1.0414)
			(drill 1.0414)
			(layers "*.Cu" "*.Mask")
			(clearance 0.381)
			(thermal_gap 0.381)
		)
		(pad "" np_thru_hole circle
			(at 3.4671 1.27 270)
			(size 1.0414 1.0414)
			(drill 1.0414)
			(layers "*.Cu" "*.Mask")
			(clearance 0.381)
			(thermal_gap 0.381)
		)
		(pad "1" smd rect
			(at 0.8255 -0.249936 270)
			(size 0.3048 0.508)
			(layers "F.Cu" "F.Mask" "F.Paste")
			(net "DELTA_L_85_5INCH_TOP_DN")
		)
		(pad "2" smd rect
			(at 0.8255 0.249936 270)
			(size 0.3048 0.508)
			(layers "F.Cu" "F.Mask" "F.Paste")
			(net "DELTA_L_85_5INCH_TOP_DP")
		)
		(pad "3" smd circle
			(at 0 0)
			(size 0 0)
			(layers "F.Cu" "F.Mask" "F.Paste")
			(net "DELTA_L_GND_1")
		)
		(zone
			(layer "F.Cu")
			(hatch none 0.5)
			(connect_pads
				(clearance 0)
			)
			(min_thickness 0.25)
			(keepout
				(tracks not_allowed)
				(vias allowed)
				(pads allowed)
				(copperpour not_allowed)
				(footprints allowed)
			)
			(placement
				(enabled no)
				(sheetname "")
			)
			(fill
				(thermal_gap 0.5)
				(thermal_bridge_width 0.5)
				(island_removal_mode 0)
			)
			(polygon
				(pts
					(xy 316.083188 -5.625846) (xy 316.083188 -5.530342) (xy 315.486288 -5.530342) (xy 315.486288 -5.123942)
					(xy 316.083188 -5.123942) (xy 316.083188 -5.03047) (xy 315.486288 -5.03047) (xy 315.486288 -4.62407)
					(xy 316.083188 -4.62407) (xy 316.083188 -4.528566) (xy 315.384688 -4.528566) (xy 315.384688 -5.625846)
				)
			)
		)
		(zone
			(layers "F.Cu" "B.Cu" "In1.Cu" "In2.Cu" "In3.Cu" "In4.Cu" "In5.Cu" "In6.Cu"
				"In7.Cu" "In8.Cu" "In9.Cu" "In10.Cu" "In11.Cu" "In12.Cu" "In13.Cu" "In14.Cu"
				"In15.Cu" "In16.Cu"
			)
			(hatch none 0.5)
			(connect_pads
				(clearance 0)
			)
			(min_thickness 0.25)
			(keepout
				(tracks not_allowed)
				(vias allowed)
				(pads allowed)
				(copperpour not_allowed)
				(footprints allowed)
			)
			(placement
				(enabled no)
				(sheetname "")
			)
			(fill
				(thermal_gap 0.5)
				(thermal_bridge_width 0.5)
				(island_removal_mode 0)
			)
			(polygon
				(pts
					(arc
						(start 313.009788 -6.347206)
						(mid 311.155588 -6.347206)
						(end 313.009788 -6.347206)
					)
				)
			)
		)
		(zone
			(layers "F.Cu" "B.Cu" "In1.Cu" "In2.Cu" "In3.Cu" "In4.Cu" "In5.Cu" "In6.Cu"
				"In7.Cu" "In8.Cu" "In9.Cu" "In10.Cu" "In11.Cu" "In12.Cu" "In13.Cu" "In14.Cu"
				"In15.Cu" "In16.Cu"
			)
			(hatch none 0.5)
			(connect_pads
				(clearance 0)
			)
			(min_thickness 0.25)
			(keepout
				(tracks not_allowed)
				(vias allowed)
				(pads allowed)
				(copperpour not_allowed)
				(footprints allowed)
			)
			(placement
				(enabled no)
				(sheetname "")
			)
			(fill
				(thermal_gap 0.5)
				(thermal_bridge_width 0.5)
				(island_removal_mode 0)
			)
			(polygon
				(pts
					(arc
						(start 313.009788 -3.807206)
						(mid 311.155588 -3.807206)
						(end 313.009788 -3.807206)
					)
				)
			)
		)
		(zone
			(layers "F.Cu" "B.Cu" "In1.Cu" "In2.Cu" "In3.Cu" "In4.Cu" "In5.Cu" "In6.Cu"
				"In7.Cu" "In8.Cu" "In9.Cu" "In10.Cu" "In11.Cu" "In12.Cu" "In13.Cu" "In14.Cu"
				"In15.Cu" "In16.Cu"
			)
			(hatch none 0.5)
			(connect_pads
				(clearance 0)
			)
			(min_thickness 0.25)
			(keepout
				(tracks not_allowed)
				(vias allowed)
				(pads allowed)
				(copperpour not_allowed)
				(footprints allowed)
			)
			(placement
				(enabled no)
				(sheetname "")
			)
			(fill
				(thermal_gap 0.5)
				(thermal_bridge_width 0.5)
				(island_removal_mode 0)
			)
			(polygon
				(pts
					(arc
						(start 319.359788 -6.347206)
						(mid 317.505588 -6.347206)
						(end 319.359788 -6.347206)
					)
				)
			)
		)
		(zone
			(layers "F.Cu" "B.Cu" "In1.Cu" "In2.Cu" "In3.Cu" "In4.Cu" "In5.Cu" "In6.Cu"
				"In7.Cu" "In8.Cu" "In9.Cu" "In10.Cu" "In11.Cu" "In12.Cu" "In13.Cu" "In14.Cu"
				"In15.Cu" "In16.Cu"
			)
			(hatch none 0.5)
			(connect_pads
				(clearance 0)
			)
			(min_thickness 0.25)
			(keepout
				(tracks not_allowed)
				(vias allowed)
				(pads allowed)
				(copperpour not_allowed)
				(footprints allowed)
			)
			(placement
				(enabled no)
				(sheetname "")
			)
			(fill
				(thermal_gap 0.5)
				(thermal_bridge_width 0.5)
				(island_removal_mode 0)
			)
			(polygon
				(pts
					(arc
						(start 319.359788 -3.807206)
						(mid 317.505588 -3.807206)
						(end 319.359788 -3.807206)
					)
				)
			)
		)
	)
)
